FILE_TYPE = MACRO_DRAWING;
SET COLOR_WIRE YELLOW;
SET COLOR_PROP MONO;
SET COLOR_DOT WHITE;
SET COLOR_ARC YELLOW;
SET COLOR_BODY GREEN;
SET COLOR_NOTE MONO;
SET PROP_DISPLAY VALUE;
SET PAGE_NUMBER P134;
FORCEADD OFFPAGE..2
(1875 4650);
FORCEPROP 2 LAST $XR0 120 
J 0
(2064 4650);
DISPLAY 0.638298 (2064 4650);
PAINT MONO (2064 4650);
FORCEPROP 2 LAST $XR1 144 
J 0
(2184 4650);
DISPLAY 0.638298 (2184 4650);
PAINT MONO (2184 4650);
FORCEPROP 2 LAST $XR2 ?
J 0
(2184 4650);
DISPLAY 0.638298 (2184 4650);
PAINT MONO (2184 4650);
FORCEPROP 1 LAST COMMENT_BODY TRUE
J 0
(1830 4555);
DISPLAY 0.872340 (1830 4555);
PAINT GREEN (1830 4555);
DISPLAY INVISIBLE (1830 4555);
FORCEPROP 1 LAST OFFPAGE TRUE
J 0
(2200 4525);
DISPLAY 0.872340 (2200 4525);
PAINT GREEN (2200 4525);
DISPLAY INVISIBLE (2200 4525);
FORCEPROP 2 LAST CDS_LIB mstr_standard
J 0
(1875 4650);
PAINT ORANGE (1875 4650);
DISPLAY INVISIBLE (1875 4650);
FORCEPROP 2 LAST PATH I1
J 0
(2200 4700);
DISPLAY 1.021277 (2200 4700);
PAINT ORANGE (2200 4700);
DISPLAY INVISIBLE (2200 4700);
FORCEADD FET_N..8
(-2875 4400);
FORCEPROP 1 LASTPIN (-2875 4600) $PN 3
J 2
(-2822 4565);
DISPLAY 0.617021 (-2822 4565);
PAINT WHITE (-2822 4565);
FORCEPROP 1 LASTPIN (-3075 4300) $PN 1
J 2
(-3072 4315);
DISPLAY 0.617021 (-3072 4315);
PAINT WHITE (-3072 4315);
FORCEPROP 1 LASTPIN (-2875 4200) $PN 2
J 2
(-2817 4200);
DISPLAY 0.617021 (-2817 4200);
PAINT WHITE (-2817 4200);
FORCEPROP 1 LAST MATERIAL FET
J 0
(-2675 4300);
DISPLAY 0.617021 (-2675 4300);
PAINT SKYBLUE (-2675 4300);
FORCEPROP 1 LAST VALUE 2N7002
J 0
(-2675 4350);
DISPLAY 0.617021 (-2675 4350);
PAINT SKYBLUE (-2675 4350);
FORCEPROP 1 LAST PART_NUMBER C79254-001
J 0
(-2675 4200);
DISPLAY 0.617021 (-2675 4200);
PAINT BLUE (-2675 4200);
FORCEPROP 1 LAST LOCATION Q7D1
J 0
(-2675 4400);
DISPLAY 0.617021 (-2675 4400);
PAINT AQUA (-2675 4400);
FORCEPROP 0 LAST ROOM THERMTRIP_PCH
J 0
(-3675 4875);
DISPLAY 1.021277 (-3675 4875);
PAINT ORANGE (-3675 4875);
DISPLAY INVISIBLE (-3675 4875);
FORCEPROP 2 LAST CDS_LOCATION Q7D1
J 0
(-2675 4400);
DISPLAY 0.617021 (-2675 4400);
PAINT AQUA (-2675 4400);
DISPLAY INVISIBLE (-2675 4400);
FORCEPROP 2 LAST SEC 1
J 0
(-2675 4500);
DISPLAY 0.680851 (-2675 4500);
PAINT MONO (-2675 4500);
DISPLAY INVISIBLE (-2675 4500);
FORCEPROP 2 LAST CDS_LIB mstr_discrete
J 0
(-3875 4725);
PAINT ORANGE (-3875 4725);
DISPLAY INVISIBLE (-3875 4725);
FORCEPROP 2 LAST SEC_TYPE SOT23
J 0
(-2675 4500);
DISPLAY 1.021277 (-2675 4500);
PAINT ORANGE (-2675 4500);
DISPLAY INVISIBLE (-2675 4500);
FORCEPROP 2 LAST BOM_COST SB
J 0
(-3725 4825);
DISPLAY 1.404255 (-3725 4825);
PAINT ORANGE (-3725 4825);
DISPLAY INVISIBLE (-3725 4825);
FORCEPROP 1 LAST PACK_TYPE SOT23
J 0
(-2675 4250);
DISPLAY 0.978723 (-2675 4250);
PAINT SKYBLUE (-2675 4250);
DISPLAY INVISIBLE (-2675 4250);
FORCEPROP 1 LAST PATH I10
J 0
(-2675 4450);
DISPLAY 0.978723 (-2675 4450);
PAINT BLUE (-2675 4450);
DISPLAY INVISIBLE (-2675 4450);
FORCEADD RES..1
(-3950 4300);
FORCEPROP 1 LASTPIN (-4050 4300) $PN 1
J 0
(-4038 4312);
DISPLAY 0.617021 (-4038 4312);
PAINT ORANGE (-4038 4312);
FORCEPROP 1 LASTPIN (-3850 4300) $PN 2
J 0
(-3888 4312);
DISPLAY 0.617021 (-3888 4312);
PAINT ORANGE (-3888 4312);
FORCEPROP 1 LAST WATTAGE 1/16W
J 2
(-3975 4150);
DISPLAY 0.617021 (-3975 4150);
PAINT SKYBLUE (-3975 4150);
FORCEPROP 1 LAST MATERIAL CHIP
J 0
(-3950 4150);
DISPLAY 0.617021 (-3950 4150);
PAINT SKYBLUE (-3950 4150);
FORCEPROP 1 LAST PACK_TYPE 0402
J 0
(-3700 4150);
DISPLAY 0.617021 (-3700 4150);
PAINT SKYBLUE (-3700 4150);
FORCEPROP 1 LAST TOLERANCE 1%
J 0
(-3950 4200);
DISPLAY 0.617021 (-3950 4200);
PAINT SKYBLUE (-3950 4200);
FORCEPROP 1 LAST VALUE 1.00K
J 2
(-3975 4200);
DISPLAY 0.617021 (-3975 4200);
PAINT SKYBLUE (-3975 4200);
FORCEPROP 1 LAST PART_NUMBER G21796-026
J 0
(-4000 4400);
DISPLAY 0.617021 (-4000 4400);
PAINT BLUE (-4000 4400);
FORCEPROP 1 LAST LOCATION R7D18
J 0
(-4000 4350);
DISPLAY 0.617021 (-4000 4350);
PAINT AQUA (-4000 4350);
FORCEPROP 0 LAST ROOM PROC_SIDEBAND
J 0
(-4000 4500);
DISPLAY 1.021277 (-4000 4500);
PAINT ORANGE (-4000 4500);
DISPLAY INVISIBLE (-4000 4500);
FORCEPROP 2 LAST CDS_LOCATION R7D18
J 0
(-4000 4350);
DISPLAY 0.617021 (-4000 4350);
PAINT AQUA (-4000 4350);
DISPLAY INVISIBLE (-4000 4350);
FORCEPROP 2 LAST SEC 1
J 0
(-4000 4500);
DISPLAY 0.680851 (-4000 4500);
PAINT MONO (-4000 4500);
DISPLAY INVISIBLE (-4000 4500);
FORCEPROP 2 LAST CDS_LIB mstr_discrete
J 0
(-3950 4300);
PAINT ORANGE (-3950 4300);
DISPLAY INVISIBLE (-3950 4300);
FORCEPROP 2 LAST SEC_TYPE 0402
J 0
(-4000 4500);
DISPLAY 1.021277 (-4000 4500);
PAINT ORANGE (-4000 4500);
DISPLAY INVISIBLE (-4000 4500);
FORCEPROP 1 LAST PATH I11
J 0
(-4000 4450);
DISPLAY 0.978723 (-4000 4450);
PAINT WHITE (-4000 4450);
DISPLAY INVISIBLE (-4000 4450);
FORCEADD GND..1
(-2875 3950);
FORCEPROP 3 LASTPIN (-2875 4000) SIG_NAME GND\g
J 0
(-2865 4010);
DISPLAY 0.659574 (-2865 4010);
PAINT MONO (-2865 4010);
DISPLAY INVISIBLE (-2865 4010);
FORCEPROP 1 LAST HDL_POWER GND
J 0
(-2875 4100);
DISPLAY 1.468085 (-2875 4100);
PAINT GREEN (-2875 4100);
DISPLAY INVISIBLE (-2875 4100);
FORCEPROP 1 LAST BODY_TYPE PLUMBING
J 0
(-2920 3907);
DISPLAY 0.340426 (-2920 3907);
PAINT GREEN (-2920 3907);
DISPLAY INVISIBLE (-2920 3907);
FORCEPROP 1 LAST SIZE 1B
J 0
(-2800 3900);
DISPLAY 1.468085 (-2800 3900);
PAINT GREEN (-2800 3900);
DISPLAY INVISIBLE (-2800 3900);
FORCEPROP 2 LAST CDS_LIB mstr_symbols
J 0
(-2875 3950);
PAINT MONO (-2875 3950);
DISPLAY INVISIBLE (-2875 3950);
FORCEPROP 2 LAST BOM_COST SB
J 0
(-2925 4025);
PAINT MONO (-2925 4025);
DISPLAY INVISIBLE (-2925 4025);
FORCEPROP 1 LAST VOLTAGE 0
J 0
(-2875 3950);
PAINT SKYBLUE (-2875 3950);
DISPLAY INVISIBLE (-2875 3950);
FORCEPROP 1 LAST PATH I12
J 0
(-2800 3950);
DISPLAY 0.872340 (-2800 3950);
PAINT AQUA (-2800 3950);
DISPLAY INVISIBLE (-2800 3950);
FORCEADD OFFPAGE..1
(-4650 4300);
FORCEPROP 2 LAST $XR0 191 
J 0
(-4902 4300);
DISPLAY 0.638298 (-4902 4300);
PAINT MONO (-4902 4300);
FORCEPROP 2 LASTPIN (-4600 4300) SIG_NAME FM_THERMTRIP_DLY
J 0
(-4585 4310);
DISPLAY 0.617021 (-4585 4310);
PAINT ORANGE (-4585 4310);
FORCEPROP 1 LAST COMMENT_BODY TRUE
J 0
(-4525 4200);
DISPLAY 1.170213 (-4525 4200);
PAINT GREEN (-4525 4200);
DISPLAY INVISIBLE (-4525 4200);
FORCEPROP 1 LAST OFFPAGE TRUE
J 0
(-4325 4175);
PAINT GREEN (-4325 4175);
DISPLAY INVISIBLE (-4325 4175);
FORCEPROP 2 LAST BOM_COST SB
J 0
(-4900 4350);
PAINT MONO (-4900 4350);
DISPLAY INVISIBLE (-4900 4350);
FORCEPROP 2 LAST CDS_LIB mstr_standard
J 0
(-4650 4300);
PAINT MONO (-4650 4300);
DISPLAY INVISIBLE (-4650 4300);
FORCEPROP 2 LAST PATH I13
J 0
(-4900 4350);
DISPLAY 1.021277 (-4900 4350);
PAINT ORANGE (-4900 4350);
DISPLAY INVISIBLE (-4900 4350);
FORCEADD P3V3_STBY..1
(700 5200);
FORCEPROP 3 LASTPIN (700 5150) SIG_NAME P3V3_STBY\g
J 0
(710 5160);
DISPLAY 0.659574 (710 5160);
PAINT MONO (710 5160);
DISPLAY INVISIBLE (710 5160);
FORCEPROP 1 LAST HDL_POWER P3V3_STBY
J 0
(400 5075);
DISPLAY 0.872340 (400 5075);
PAINT ORANGE (400 5075);
DISPLAY INVISIBLE (400 5075);
FORCEPROP 1 LAST BODY_TYPE PLUMBING
J 0
(655 5157);
DISPLAY 0.340426 (655 5157);
PAINT GREEN (655 5157);
DISPLAY INVISIBLE (655 5157);
FORCEPROP 2 LAST CDS_LIB mstr_symbols
J 0
(700 5200);
PAINT ORANGE (700 5200);
DISPLAY INVISIBLE (700 5200);
FORCEPROP 1 LAST SIZE 1B
J 0
(745 5222);
DISPLAY 0.340426 (745 5222);
PAINT GREEN (745 5222);
DISPLAY INVISIBLE (745 5222);
FORCEPROP 1 LAST VOLTAGE 3.3V
J 0
(655 5157);
DISPLAY 0.340426 (655 5157);
PAINT SKYBLUE (655 5157);
DISPLAY INVISIBLE (655 5157);
FORCEPROP 1 LAST PATH I2
J 0
(745 5202);
DISPLAY 0.340426 (745 5202);
PAINT GREEN (745 5202);
DISPLAY INVISIBLE (745 5202);
FORCEADD RES..2
(700 4925);
FORCEPROP 1 LASTPIN (700 5025) $PN 1
J 0
(705 4987);
DISPLAY 0.617021 (705 4987);
PAINT ORANGE (705 4987);
FORCEPROP 1 LASTPIN (700 4825) $PN 2
J 0
(705 4835);
DISPLAY 0.617021 (705 4835);
PAINT ORANGE (705 4835);
FORCEPROP 1 LAST WATTAGE 1/16W
J 0
(740 4900);
DISPLAY 0.617021 (740 4900);
PAINT SKYBLUE (740 4900);
FORCEPROP 1 LAST MATERIAL CHIP
J 0
(740 4850);
DISPLAY 0.617021 (740 4850);
PAINT SKYBLUE (740 4850);
FORCEPROP 1 LAST PACK_TYPE 0402
J 0
(740 4750);
DISPLAY 0.617021 (740 4750);
PAINT SKYBLUE (740 4750);
FORCEPROP 1 LAST TOLERANCE 1%
J 0
(745 4950);
DISPLAY 0.617021 (745 4950);
PAINT SKYBLUE (745 4950);
FORCEPROP 1 LAST VALUE 4.75K
J 0
(745 5000);
DISPLAY 0.617021 (745 5000);
PAINT SKYBLUE (745 5000);
FORCEPROP 1 LAST PART_NUMBER G21796-072
J 0
(740 4800);
DISPLAY 0.617021 (740 4800);
PAINT BLUE (740 4800);
FORCEPROP 1 LAST LOCATION R2P17
J 0
(745 5050);
DISPLAY 0.617021 (745 5050);
PAINT AQUA (745 5050);
FORCEPROP 2 LAST ROOM THERMTRIP_PCH
J 0
(750 5100);
PAINT PEACH (750 5100);
DISPLAY INVISIBLE (750 5100);
FORCEPROP 2 LAST SEC 1
J 0
(750 5150);
DISPLAY 0.680851 (750 5150);
PAINT MONO (750 5150);
DISPLAY INVISIBLE (750 5150);
FORCEPROP 2 LAST SEC_TYPE 0402
J 0
(750 5150);
DISPLAY 1.021277 (750 5150);
PAINT ORANGE (750 5150);
DISPLAY INVISIBLE (750 5150);
FORCEPROP 2 LAST CDS_LIB mstr_discrete
J 0
(700 4925);
PAINT ORANGE (700 4925);
DISPLAY INVISIBLE (700 4925);
FORCEPROP 2 LAST BOM_COST SB
J 0
(750 5100);
PAINT MONO (750 5100);
DISPLAY INVISIBLE (750 5100);
FORCEPROP 1 LAST PATH I3
J 0
(750 5100);
DISPLAY 0.978723 (750 5100);
PAINT WHITE (750 5100);
DISPLAY INVISIBLE (750 5100);
FORCEADD FET_N..8
(700 4375);
FORCEPROP 1 LASTPIN (700 4575) $PN 3
J 2
(753 4540);
DISPLAY 0.617021 (753 4540);
PAINT WHITE (753 4540);
FORCEPROP 1 LASTPIN (500 4275) $PN 1
J 2
(503 4290);
DISPLAY 0.617021 (503 4290);
PAINT WHITE (503 4290);
FORCEPROP 1 LASTPIN (700 4175) $PN 2
J 2
(758 4175);
DISPLAY 0.617021 (758 4175);
PAINT WHITE (758 4175);
FORCEPROP 1 LAST MATERIAL FET
J 0
(900 4275);
DISPLAY 0.617021 (900 4275);
PAINT SKYBLUE (900 4275);
FORCEPROP 1 LAST VALUE 2N7002
J 0
(900 4325);
DISPLAY 0.617021 (900 4325);
PAINT SKYBLUE (900 4325);
FORCEPROP 1 LAST PART_NUMBER C79254-001
J 0
(900 4175);
DISPLAY 0.617021 (900 4175);
PAINT BLUE (900 4175);
FORCEPROP 1 LAST LOCATION Q8D2
J 0
(900 4375);
DISPLAY 0.617021 (900 4375);
PAINT AQUA (900 4375);
FORCEPROP 0 LAST ROOM THERMTRIP_PCH
J 0
(-100 4850);
DISPLAY 1.021277 (-100 4850);
PAINT ORANGE (-100 4850);
DISPLAY INVISIBLE (-100 4850);
FORCEPROP 2 LAST SEC 1
J 0
(900 4475);
DISPLAY 0.680851 (900 4475);
PAINT MONO (900 4475);
DISPLAY INVISIBLE (900 4475);
FORCEPROP 2 LAST SEC_TYPE SOT23
J 0
(900 4475);
DISPLAY 1.021277 (900 4475);
PAINT ORANGE (900 4475);
DISPLAY INVISIBLE (900 4475);
FORCEPROP 2 LAST BOM_COST SB
J 0
(-150 4800);
DISPLAY 1.404255 (-150 4800);
PAINT ORANGE (-150 4800);
DISPLAY INVISIBLE (-150 4800);
FORCEPROP 2 LAST CDS_LIB mstr_discrete
J 0
(700 4375);
PAINT ORANGE (700 4375);
DISPLAY INVISIBLE (700 4375);
FORCEPROP 1 LAST PACK_TYPE SOT23
J 0
(900 4225);
DISPLAY 0.978723 (900 4225);
PAINT SKYBLUE (900 4225);
DISPLAY INVISIBLE (900 4225);
FORCEPROP 1 LAST PATH I4
J 0
(900 4425);
DISPLAY 0.978723 (900 4425);
PAINT BLUE (900 4425);
DISPLAY INVISIBLE (900 4425);
FORCEADD OFFPAGE..4
(1850 3925);
FORCEPROP 2 LAST $XR0 119 
J 0
(2036 3925);
DISPLAY 0.638298 (2036 3925);
PAINT MONO (2036 3925);
FORCEPROP 2 LAST $XR1 126 
J 0
(2156 3925);
DISPLAY 0.638298 (2156 3925);
PAINT MONO (2156 3925);
FORCEPROP 1 LAST COMMENT_BODY TRUE
J 0
(1825 3825);
DISPLAY 0.872340 (1825 3825);
PAINT GREEN (1825 3825);
DISPLAY INVISIBLE (1825 3825);
FORCEPROP 1 LAST OFFPAGE TRUE
J 0
(2175 3800);
DISPLAY 0.872340 (2175 3800);
PAINT GREEN (2175 3800);
DISPLAY INVISIBLE (2175 3800);
FORCEPROP 2 LAST CDS_LIB mstr_standard
J 0
(1850 3925);
PAINT ORANGE (1850 3925);
DISPLAY INVISIBLE (1850 3925);
FORCEPROP 2 LAST PATH I5
J 0
(2175 3975);
DISPLAY 1.021277 (2175 3975);
PAINT ORANGE (2175 3975);
DISPLAY INVISIBLE (2175 3975);
FORCEADD OFFPAGE..1
(-500 4275);
FORCEPROP 2 LAST $XR0 191 
J 0
(-752 4275);
DISPLAY 0.638298 (-752 4275);
PAINT MONO (-752 4275);
FORCEPROP 2 LAST $XR1 145 
J 0
(-872 4275);
DISPLAY 0.638298 (-872 4275);
PAINT MONO (-872 4275);
FORCEPROP 2 LAST $XR2 146 
J 0
(-992 4275);
DISPLAY 0.638298 (-992 4275);
PAINT MONO (-992 4275);
FORCEPROP 2 LAST $XR3 184 
J 0
(-1112 4275);
DISPLAY 0.638298 (-1112 4275);
PAINT MONO (-1112 4275);
FORCEPROP 1 LAST COMMENT_BODY TRUE
J 0
(-375 4175);
DISPLAY 0.872340 (-375 4175);
PAINT GREEN (-375 4175);
DISPLAY INVISIBLE (-375 4175);
FORCEPROP 1 LAST OFFPAGE TRUE
J 0
(-175 4150);
DISPLAY 0.872340 (-175 4150);
PAINT GREEN (-175 4150);
DISPLAY INVISIBLE (-175 4150);
FORCEPROP 2 LAST CDS_LIB mstr_standard
J 0
(-500 4275);
PAINT ORANGE (-500 4275);
DISPLAY INVISIBLE (-500 4275);
FORCEPROP 2 LAST PATH I6
J 0
(-750 4325);
DISPLAY 1.021277 (-750 4325);
PAINT ORANGE (-750 4325);
DISPLAY INVISIBLE (-750 4325);
FORCEADD OFFPAGE..2
(-1925 4625);
FORCEPROP 2 LAST $XR0 118 
J 0
(-1736 4625);
DISPLAY 0.638298 (-1736 4625);
PAINT MONO (-1736 4625);
FORCEPROP 1 LAST COMMENT_BODY TRUE
J 0
(-1970 4530);
DISPLAY 1.170213 (-1970 4530);
PAINT GREEN (-1970 4530);
DISPLAY INVISIBLE (-1970 4530);
FORCEPROP 1 LAST OFFPAGE TRUE
J 0
(-1600 4500);
PAINT GREEN (-1600 4500);
DISPLAY INVISIBLE (-1600 4500);
FORCEPROP 2 LAST CDS_LIB mstr_standard
J 0
(-1925 4625);
PAINT MONO (-1925 4625);
DISPLAY INVISIBLE (-1925 4625);
FORCEPROP 2 LAST BOM_COST SB
J 0
(-1725 4675);
PAINT MONO (-1725 4675);
DISPLAY INVISIBLE (-1725 4675);
FORCEPROP 2 LAST PATH I7
J 0
(-1725 4675);
DISPLAY 1.021277 (-1725 4675);
PAINT ORANGE (-1725 4675);
DISPLAY INVISIBLE (-1725 4675);
FORCEADD P1V05_PCH_STBY..1
(-2875 5100);
FORCEPROP 3 LASTPIN (-2875 5050) SIG_NAME P1V05_PCH_STBY\g
J 0
(-2865 5060);
DISPLAY 0.659574 (-2865 5060);
PAINT MONO (-2865 5060);
DISPLAY INVISIBLE (-2865 5060);
FORCEPROP 1 LAST HDL_POWER P1V05_PCH_STBY
J 0
(-2875 5150);
DISPLAY 0.872340 (-2875 5150);
PAINT GREEN (-2875 5150);
DISPLAY INVISIBLE (-2875 5150);
FORCEPROP 1 LAST BODY_TYPE PLUMBING
J 0
(-2920 5057);
DISPLAY 0.340426 (-2920 5057);
PAINT GREEN (-2920 5057);
DISPLAY INVISIBLE (-2920 5057);
FORCEPROP 2 LAST CDS_LIB mstr_symbols
J 0
(-2875 5100);
PAINT ORANGE (-2875 5100);
DISPLAY INVISIBLE (-2875 5100);
FORCEPROP 1 LAST VOLTAGE 1.05V
J 0
(-2920 5057);
DISPLAY 0.340426 (-2920 5057);
PAINT SKYBLUE (-2920 5057);
DISPLAY INVISIBLE (-2920 5057);
FORCEPROP 1 LAST PATH I8
J 0
(-2825 5125);
DISPLAY 0.872340 (-2825 5125);
PAINT AQUA (-2825 5125);
DISPLAY INVISIBLE (-2825 5125);
FORCEADD RES..2
(-2875 4875);
FORCEPROP 1 LASTPIN (-2875 4975) $PN 1
J 0
(-2870 4937);
DISPLAY 0.617021 (-2870 4937);
PAINT ORANGE (-2870 4937);
FORCEPROP 1 LASTPIN (-2875 4775) $PN 2
J 0
(-2870 4785);
DISPLAY 0.617021 (-2870 4785);
PAINT ORANGE (-2870 4785);
FORCEPROP 1 LAST WATTAGE 1/16W
J 0
(-2835 4850);
DISPLAY 0.617021 (-2835 4850);
PAINT SKYBLUE (-2835 4850);
FORCEPROP 1 LAST MATERIAL CHIP
J 0
(-2835 4800);
DISPLAY 0.617021 (-2835 4800);
PAINT SKYBLUE (-2835 4800);
FORCEPROP 1 LAST PACK_TYPE 0402
J 0
(-2835 4700);
DISPLAY 0.617021 (-2835 4700);
PAINT SKYBLUE (-2835 4700);
FORCEPROP 1 LAST TOLERANCE 1%
J 0
(-2830 4900);
DISPLAY 0.617021 (-2830 4900);
PAINT SKYBLUE (-2830 4900);
FORCEPROP 1 LAST VALUE 10.0K
J 0
(-2830 4950);
DISPLAY 0.617021 (-2830 4950);
PAINT SKYBLUE (-2830 4950);
FORCEPROP 1 LAST PART_NUMBER G21796-016
J 0
(-2835 4750);
DISPLAY 0.617021 (-2835 4750);
PAINT BLUE (-2835 4750);
FORCEPROP 1 LAST LOCATION R7C21
J 0
(-2830 5000);
DISPLAY 0.617021 (-2830 5000);
PAINT AQUA (-2830 5000);
FORCEPROP 2 LAST ROOM THERMTRIP_PCH
J 0
(-2825 5050);
PAINT PEACH (-2825 5050);
DISPLAY INVISIBLE (-2825 5050);
FORCEPROP 2 LAST CDS_LOCATION R7C21
J 0
(-2830 5000);
DISPLAY 0.617021 (-2830 5000);
PAINT AQUA (-2830 5000);
DISPLAY INVISIBLE (-2830 5000);
FORCEPROP 2 LAST SEC 1
J 0
(-2825 5100);
DISPLAY 0.680851 (-2825 5100);
PAINT MONO (-2825 5100);
DISPLAY INVISIBLE (-2825 5100);
FORCEPROP 2 LAST CDS_LIB mstr_discrete
J 0
(-2875 4875);
PAINT ORANGE (-2875 4875);
DISPLAY INVISIBLE (-2875 4875);
FORCEPROP 2 LAST SEC_TYPE 0402
J 0
(-2825 5100);
DISPLAY 1.021277 (-2825 5100);
PAINT ORANGE (-2825 5100);
DISPLAY INVISIBLE (-2825 5100);
FORCEPROP 2 LAST BOM_COST SB
J 0
(-2825 5050);
PAINT MONO (-2825 5050);
DISPLAY INVISIBLE (-2825 5050);
FORCEPROP 1 LAST PATH I9
J 0
(-2825 5050);
DISPLAY 0.978723 (-2825 5050);
PAINT WHITE (-2825 5050);
DISPLAY INVISIBLE (-2825 5050);
FORCEADD INTEL_CORP_BPAGE..1
(2650 500);
FORCEPROP 1 LAST CDS_CON_LAST_MODIFIED Tue Dec 01 11:52:01 2015
J 0
(1225 825);
PAINT ORANGE (1225 825);
DISPLAY INVISIBLE (1225 825);
FORCEPROP 1 LAST CUSTOM_TXT_CDS <CURRENT_DESIGN_SHEET> OF <TOTAL_DESIGN_SHEETS>
J 0
(2150 525);
PAINT GREEN (2150 525);
FORCEPROP 1 LAST CUSTOM_TXT_CDS <CON_LAST_MODIFIED>
J 0
(725 850);
PAINT GREEN (725 850);
FORCEPROP 2 LAST CUSTOM_TXT_CDS <XR_PAGE_TITLE>
J 0
(-5240 5750);
DISPLAY 0.638298 (-5240 5750);
PAINT PINK (-5240 5750);
DISPLAY INVISIBLE (-5240 5750);
FORCEPROP 1 LAST SCH_ADDRESS1 2200 Mission College Blvd.
J 0
(-1325 625);
DISPLAY 0.617021 (-1325 625);
PAINT GREEN (-1325 625);
FORCEPROP 1 LAST SCH_ADDRESS2 P.O. BOX 58119
J 0
(-1325 575);
DISPLAY 0.617021 (-1325 575);
PAINT GREEN (-1325 575);
FORCEPROP 1 LAST SCH_ADDRESS3 Santa Clara, CA 95052-8119
J 0
(-1325 525);
DISPLAY 0.617021 (-1325 525);
PAINT GREEN (-1325 525);
FORCEPROP 1 LAST SCH_TITLE THERMTRIP AND FIVRBREAK
J 0
(-5300 550);
DISPLAY 1.212766 (-5300 550);
PAINT ORANGE (-5300 550);
FORCEPROP 1 LAST SCH_NUMBER H4694802
J 0
(1350 650);
DISPLAY 1.212766 (1350 650);
PAINT YELLOW (1350 650);
FORCEPROP 1 LAST SCH_DEPT BESD
J 1
(-1800 600);
DISPLAY 1.212766 (-1800 600);
PAINT YELLOW (-1800 600);
FORCEPROP 1 LAST SCH_REV 2.420
J 0
(2400 650);
DISPLAY 0.978723 (2400 650);
PAINT YELLOW (2400 650);
FORCEPROP 2 LAST PAGE_BORDER TRUE
J 0
(-5240 5750);
DISPLAY 0.851064 (-5240 5750);
PAINT PINK (-5240 5750);
DISPLAY INVISIBLE (-5240 5750);
FORCEPROP 2 LAST CDS_LIB mstr_symbols
J 0
(2650 500);
PAINT MONO (2650 500);
DISPLAY INVISIBLE (2650 500);
FORCEPROP 1 LAST COMMENT_BODY TRUE
J 0
(2662 512);
DISPLAY 0.468085 (2662 512);
PAINT GREEN (2662 512);
DISPLAY INVISIBLE (2662 512);
FORCEPROP 2 LAST CDS_XR_PAGE_TITLE CR-134 : @BASEBOARD_FAB2_LIB.BASEBOARD_FAB2(SCH_1):PAGE134
J 0
(-5240 5750);
DISPLAY 0.638298 (-5240 5750);
PAINT PINK (-5240 5750);
DISPLAY INVISIBLE (-5240 5750);
WIRE 16 -1 (-2875 4200)(-2875 4000);
WIRE 16 -1 (700 5150)(700 5025);
WIRE 16 -1 (-2875 4975)(-2875 5050);
WIRE 16 -1 (-4600 4300)(-4050 4300);
WIRE 16 -1 (-3850 4300)(-3075 4300);
FORCEPROP 2 LAST SIG_NAME FM_THERMTRIP_DLY_R
J 0
(-3785 4310);
DISPLAY 0.617021 (-3785 4310);
PAINT ORANGE (-3785 4310);
FORCEPROP 2 LASTPROP $XRERR UNIQUE?
J 0
(-4025 4310);
DISPLAY 0.638298 (-4025 4310);
PAINT MONO (-4025 4310);
DISPLAY INVISIBLE (-4025 4310);
WIRE 16 -1 (-1975 4625)(-2875 4625);
FORCEPROP 2 LAST SIG_NAME FM_PCH_LVC1_THERMTRIP_N
J 0
(-2710 4635);
DISPLAY 0.617021 (-2710 4635);
PAINT ORANGE (-2710 4635);
WIRE 16 -1 (-2875 4775)(-2875 4625);
WIRE 16 -1 (-2875 4625)(-2875 4600);
WIRE 16 -1 (500 4275)(-450 4275);
FORCEPROP 2 LAST SIG_NAME RST_PLTRST_BUF_N
J 0
(-360 4285);
DISPLAY 0.617021 (-360 4285);
PAINT ORANGE (-360 4285);
WIRE 16 -1 (700 4175)(700 3925);
WIRE 16 -1 (700 3925)(1800 3925);
FORCEPROP 2 LAST SIG_NAME FM_PCH_BMC_THERMTRIP_EXI_STRAP_N
J 0
(965 3935);
DISPLAY 0.617021 (965 3935);
PAINT ORANGE (965 3935);
WIRE 16 -1 (700 4825)(700 4650);
WIRE 16 -1 (700 4650)(1825 4650);
FORCEPROP 2 LAST SIG_NAME FM_PCH_BMC_THERMTRIP_N
J 0
(990 4660);
DISPLAY 0.617021 (990 4660);
PAINT ORANGE (990 4660);
WIRE 16 -1 (700 4575)(700 4650);
WIRE 16 273 (-5175 3025)(2375 3025);
DOT 1 (700 4650);
DOT 1 (-2875 4625);
QUIT
